(kicad_pcb
	(version 20260206)
	(generator "pcbnew")
	(generator_version "10.0")
	(general
		(thickness 1.6)
		(legacy_teardrops no)
	)
	(paper "A4")
	(title_block
		(title "baseboard — 13948-1b.1110WZS1818.brd")
		(comment 1 "Honey Badger (Wiwynn) / footprints 1709-1712 of 2523")
	)
	(layers
		(0 "F.Cu" signal "TOP")
		(4 "In1.Cu" signal "L2GND")
		(6 "In2.Cu" signal "L3")
		(8 "In3.Cu" signal "L4VCC")
		(10 "In4.Cu" signal "L5VCC")
		(12 "In5.Cu" signal "L6")
		(14 "In6.Cu" signal "L7GND")
		(2 "B.Cu" signal "BOTTOM")
		(9 "F.Adhes" user "F.Adhesive")
		(11 "B.Adhes" user "B.Adhesive")
		(13 "F.Paste" user "Package Geometry/Pastemask Top")
		(15 "B.Paste" user "Package Geometry/Pastemask Bottom")
		(5 "F.SilkS" user "Ref Des/Silkscreen Top")
		(7 "B.SilkS" user "Ref Des/Silkscreen Bottom")
		(1 "F.Mask" user "Board Geometry/Soldermask Top")
		(3 "B.Mask" user "Board Geometry/Soldermask Bottom")
		(17 "Dwgs.User" user "User.Drawings")
		(19 "Cmts.User" user "User.Comments")
		(21 "Eco1.User" user "User.Eco1")
		(23 "Eco2.User" user "User.Eco2")
		(25 "Edge.Cuts" user "Board Geometry/Outline")
		(27 "Margin" user)
		(31 "F.CrtYd" user "Package Geometry/Place Bound Top")
		(29 "B.CrtYd" user "Package Geometry/Place Bound Bottom")
		(35 "F.Fab" user "Ref Des/Assembly Top")
		(33 "B.Fab" user "Ref Des/Assembly Bottom")
	)
	(footprint ""
		(layer "F.Cu")
		(at 142.348966 -52.324)
		(property "Reference" "SU58"
			(at 0 0 0)
			(layer "F.SilkS")
			(hide yes)
			(effects
				(font
					(size 1.27 1.27)
				)
			)
		)
		(property "Value" "S29GL128S10TFIV20-GP"
			(at -0.1778 -20.32 0)
			(unlocked yes)
			(layer "F.Fab")
			(hide yes)
			(effects
				(font
					(size 1.016 1.016)
					(thickness 0.1524)
				)
			)
		)
		(property "Device Type" "TSOP56-1H48"
			(at -0.1778 -22.225 0)
			(unlocked yes)
			(layer "F.Fab")
			(hide yes)
			(effects
				(font
					(size 1.016 1.016)
					(thickness 0.1524)
				)
			)
		)
		(duplicate_pad_numbers_are_jumpers no)
		(fp_line
			(start -7.5438 -8.5598)
			(end -7.5438 8.5598)
			(stroke
				(width 0.1524)
				(type default)
			)
			(layer "F.SilkS")
		)
		(fp_line
			(start -7.5438 -0.4318)
			(end -7.112 0)
			(stroke
				(width 0.1524)
				(type default)
			)
			(layer "F.SilkS")
		)
		(fp_line
			(start -7.5438 8.5598)
			(end 6.8326 8.5598)
			(stroke
				(width 0.1524)
				(type default)
			)
			(layer "F.SilkS")
		)
		(fp_line
			(start -7.366 8.5598)
			(end -7.366 10.795)
			(stroke
				(width 0.508)
				(type default)
			)
			(layer "F.SilkS")
		)
		(fp_line
			(start -7.112 0)
			(end -7.5438 0.4318)
			(stroke
				(width 0.1524)
				(type default)
			)
			(layer "F.SilkS")
		)
		(fp_line
			(start 6.8326 -8.5598)
			(end -7.5438 -8.5598)
			(stroke
				(width 0.1524)
				(type default)
			)
			(layer "F.SilkS")
		)
		(fp_line
			(start 6.8326 8.5598)
			(end 6.8326 -8.5598)
			(stroke
				(width 0.1524)
				(type default)
			)
			(layer "F.SilkS")
		)
		(fp_poly
			(pts
				(xy -7.62 11.049) (xy 7.62 11.049) (xy 7.62 -11.049) (xy -7.62 -11.049)
			)
			(stroke
				(width 0)
				(type default)
			)
			(fill no)
			(layer "F.CrtYd")
		)
		(fp_poly
			(pts
				(xy -7.62 -11.049) (xy 7.62 -11.049) (xy 7.62 11.049) (xy -7.62 11.049)
			)
			(stroke
				(width 0)
				(type default)
			)
			(fill no)
			(layer "F.Fab")
		)
		(pad "1" smd rect
			(at -6.75005 9.6139)
			(size 0.3048 1.524)
			(layers "F.Cu" "F.Mask" "F.Paste")
			(net "Net_176")
		)
		(pad "2" smd rect
			(at -6.24967 9.6139)
			(size 0.3048 1.524)
			(layers "F.Cu" "F.Mask" "F.Paste")
			(net "XM_ADDR_23")
		)
		(pad "3" smd rect
			(at -5.75056 9.6139)
			(size 0.3048 1.524)
			(layers "F.Cu" "F.Mask" "F.Paste")
			(net "XM_ADDR_16")
		)
		(pad "4" smd rect
			(at -5.25018 9.6139)
			(size 0.3048 1.524)
			(layers "F.Cu" "F.Mask" "F.Paste")
			(net "XM_ADDR_15")
		)
		(pad "5" smd rect
			(at -4.7498 9.6139)
			(size 0.3048 1.524)
			(layers "F.Cu" "F.Mask" "F.Paste")
			(net "XM_ADDR_14")
		)
		(pad "6" smd rect
			(at -4.24942 9.6139)
			(size 0.3048 1.524)
			(layers "F.Cu" "F.Mask" "F.Paste")
			(net "XM_ADDR_13")
		)
		(pad "7" smd rect
			(at -3.75031 9.6139)
			(size 0.3048 1.524)
			(layers "F.Cu" "F.Mask" "F.Paste")
			(net "XM_ADDR_12")
		)
		(pad "8" smd rect
			(at -3.24993 9.6139)
			(size 0.3048 1.524)
			(layers "F.Cu" "F.Mask" "F.Paste")
			(net "XM_ADDR_11")
		)
		(pad "9" smd rect
			(at -2.74955 9.6139)
			(size 0.3048 1.524)
			(layers "F.Cu" "F.Mask" "F.Paste")
			(net "XM_ADDR_10")
		)
		(pad "10" smd rect
			(at -2.25044 9.6139)
			(size 0.3048 1.524)
			(layers "F.Cu" "F.Mask" "F.Paste")
			(net "XM_ADDR_9")
		)
		(pad "11" smd rect
			(at -1.75006 9.6139)
			(size 0.3048 1.524)
			(layers "F.Cu" "F.Mask" "F.Paste")
			(net "XM_ADDR_20")
		)
		(pad "12" smd rect
			(at -1.24968 9.6139)
			(size 0.3048 1.524)
			(layers "F.Cu" "F.Mask" "F.Paste")
			(net "XM_ADDR_21")
		)
		(pad "13" smd rect
			(at -0.75057 9.6139)
			(size 0.3048 1.524)
			(layers "F.Cu" "F.Mask" "F.Paste")
			(net "XM_WE_N")
		)
		(pad "14" smd rect
			(at -0.25019 9.6139)
			(size 0.3048 1.524)
			(layers "F.Cu" "F.Mask" "F.Paste")
			(net "XM_F_RST_N")
		)
		(pad "15" smd rect
			(at 0.25019 9.6139)
			(size 0.3048 1.524)
			(layers "F.Cu" "F.Mask" "F.Paste")
			(net "XM_ADDR_22")
		)
		(pad "16" smd rect
			(at 0.75057 9.6139)
			(size 0.3048 1.524)
			(layers "F.Cu" "F.Mask" "F.Paste")
			(net "IOC_WP_N")
		)
		(pad "17" smd rect
			(at 1.24968 9.6139)
			(size 0.3048 1.524)
			(layers "F.Cu" "F.Mask" "F.Paste")
			(net "Net_1019")
		)
		(pad "18" smd rect
			(at 1.75006 9.6139)
			(size 0.3048 1.524)
			(layers "F.Cu" "F.Mask" "F.Paste")
			(net "XM_ADDR_19")
		)
		(pad "19" smd rect
			(at 2.25044 9.6139)
			(size 0.3048 1.524)
			(layers "F.Cu" "F.Mask" "F.Paste")
			(net "XM_ADDR_18")
		)
		(pad "20" smd rect
			(at 2.74955 9.6139)
			(size 0.3048 1.524)
			(layers "F.Cu" "F.Mask" "F.Paste")
			(net "XM_ADDR_8")
		)
		(pad "21" smd rect
			(at 3.24993 9.6139)
			(size 0.3048 1.524)
			(layers "F.Cu" "F.Mask" "F.Paste")
			(net "XM_ADDR_7")
		)
		(pad "22" smd rect
			(at 3.75031 9.6139)
			(size 0.3048 1.524)
			(layers "F.Cu" "F.Mask" "F.Paste")
			(net "XM_ADDR_6")
		)
		(pad "23" smd rect
			(at 4.24942 9.6139)
			(size 0.3048 1.524)
			(layers "F.Cu" "F.Mask" "F.Paste")
			(net "XM_ADDR_5")
		)
		(pad "24" smd rect
			(at 4.7498 9.6139)
			(size 0.3048 1.524)
			(layers "F.Cu" "F.Mask" "F.Paste")
			(net "XM_ADDR_4")
		)
		(pad "25" smd rect
			(at 5.25018 9.6139)
			(size 0.3048 1.524)
			(layers "F.Cu" "F.Mask" "F.Paste")
			(net "XM_ADDR_3")
		)
		(pad "26" smd rect
			(at 5.75056 9.6139)
			(size 0.3048 1.524)
			(layers "F.Cu" "F.Mask" "F.Paste")
			(net "XM_ADDR_2")
		)
		(pad "27" smd rect
			(at 6.24967 9.6139)
			(size 0.3048 1.524)
			(layers "F.Cu" "F.Mask" "F.Paste")
			(net "Net_1020")
		)
		(pad "28" smd rect
			(at 6.75005 9.6139)
			(size 0.3048 1.524)
			(layers "F.Cu" "F.Mask" "F.Paste")
			(net "Net_1021")
		)
		(pad "29" smd rect
			(at 6.75005 -9.6139)
			(size 0.3048 1.524)
			(layers "F.Cu" "F.Mask" "F.Paste")
			(net "P1V8_C")
		)
		(pad "30" smd rect
			(at 6.24967 -9.6139)
			(size 0.3048 1.524)
			(layers "F.Cu" "F.Mask" "F.Paste")
			(net "Net_1018")
		)
		(pad "31" smd rect
			(at 5.75056 -9.6139)
			(size 0.3048 1.524)
			(layers "F.Cu" "F.Mask" "F.Paste")
			(net "XM_ADDR_1")
		)
		(pad "32" smd rect
			(at 5.25018 -9.6139)
			(size 0.3048 1.524)
			(layers "F.Cu" "F.Mask" "F.Paste")
			(net "XM_NOR_CS_N")
		)
		(pad "33" smd rect
			(at 4.7498 -9.6139)
			(size 0.3048 1.524)
			(layers "F.Cu" "F.Mask" "F.Paste")
			(net "GND")
		)
		(pad "34" smd rect
			(at 4.24942 -9.6139)
			(size 0.3048 1.524)
			(layers "F.Cu" "F.Mask" "F.Paste")
			(net "XM_OE_N")
		)
		(pad "35" smd rect
			(at 3.75031 -9.6139)
			(size 0.3048 1.524)
			(layers "F.Cu" "F.Mask" "F.Paste")
			(net "XM_DATA_0")
		)
		(pad "36" smd rect
			(at 3.24993 -9.6139)
			(size 0.3048 1.524)
			(layers "F.Cu" "F.Mask" "F.Paste")
			(net "XM_DATA_8")
		)
		(pad "37" smd rect
			(at 2.74955 -9.6139)
			(size 0.3048 1.524)
			(layers "F.Cu" "F.Mask" "F.Paste")
			(net "XM_DATA_1")
		)
		(pad "38" smd rect
			(at 2.25044 -9.6139)
			(size 0.3048 1.524)
			(layers "F.Cu" "F.Mask" "F.Paste")
			(net "XM_DATA_9")
		)
		(pad "39" smd rect
			(at 1.75006 -9.6139)
			(size 0.3048 1.524)
			(layers "F.Cu" "F.Mask" "F.Paste")
			(net "XM_DATA_2")
		)
		(pad "40" smd rect
			(at 1.24968 -9.6139)
			(size 0.3048 1.524)
			(layers "F.Cu" "F.Mask" "F.Paste")
			(net "XM_DATA_10")
		)
		(pad "41" smd rect
			(at 0.75057 -9.6139)
			(size 0.3048 1.524)
			(layers "F.Cu" "F.Mask" "F.Paste")
			(net "XM_DATA_3")
		)
		(pad "42" smd rect
			(at 0.25019 -9.6139)
			(size 0.3048 1.524)
			(layers "F.Cu" "F.Mask" "F.Paste")
			(net "XM_DATA_11")
		)
		(pad "43" smd rect
			(at -0.25019 -9.6139)
			(size 0.3048 1.524)
			(layers "F.Cu" "F.Mask" "F.Paste")
			(net "P3V3")
		)
		(pad "44" smd rect
			(at -0.75057 -9.6139)
			(size 0.3048 1.524)
			(layers "F.Cu" "F.Mask" "F.Paste")
			(net "XM_DATA_4")
		)
		(pad "45" smd rect
			(at -1.24968 -9.6139)
			(size 0.3048 1.524)
			(layers "F.Cu" "F.Mask" "F.Paste")
			(net "XM_DATA_12")
		)
		(pad "46" smd rect
			(at -1.75006 -9.6139)
			(size 0.3048 1.524)
			(layers "F.Cu" "F.Mask" "F.Paste")
			(net "XM_DATA_5")
		)
		(pad "47" smd rect
			(at -2.25044 -9.6139)
			(size 0.3048 1.524)
			(layers "F.Cu" "F.Mask" "F.Paste")
			(net "XM_DATA_13")
		)
		(pad "48" smd rect
			(at -2.74955 -9.6139)
			(size 0.3048 1.524)
			(layers "F.Cu" "F.Mask" "F.Paste")
			(net "XM_DATA_6")
		)
		(pad "49" smd rect
			(at -3.24993 -9.6139)
			(size 0.3048 1.524)
			(layers "F.Cu" "F.Mask" "F.Paste")
			(net "XM_DATA_14")
		)
		(pad "50" smd rect
			(at -3.75031 -9.6139)
			(size 0.3048 1.524)
			(layers "F.Cu" "F.Mask" "F.Paste")
			(net "XM_DATA_7")
		)
		(pad "51" smd rect
			(at -4.24942 -9.6139)
			(size 0.3048 1.524)
			(layers "F.Cu" "F.Mask" "F.Paste")
			(net "XM_DATA_15")
		)
		(pad "52" smd rect
			(at -4.7498 -9.6139)
			(size 0.3048 1.524)
			(layers "F.Cu" "F.Mask" "F.Paste")
			(net "GND")
		)
		(pad "53" smd rect
			(at -5.25018 -9.6139)
			(size 0.3048 1.524)
			(layers "F.Cu" "F.Mask" "F.Paste")
			(net "Net_260")
		)
		(pad "54" smd rect
			(at -5.75056 -9.6139)
			(size 0.3048 1.524)
			(layers "F.Cu" "F.Mask" "F.Paste")
			(net "XM_ADDR_17")
		)
		(pad "55" smd rect
			(at -6.24967 -9.6139)
			(size 0.3048 1.524)
			(layers "F.Cu" "F.Mask" "F.Paste")
			(net "Net_1022")
		)
		(pad "56" smd rect
			(at -6.75005 -9.6139)
			(size 0.3048 1.524)
			(layers "F.Cu" "F.Mask" "F.Paste")
			(net "Net_175")
		)
	)
	(footprint ""
		(layer "F.Cu")
		(at 179.061872 -204.211936 -90)
		(property "Reference" "U23"
			(at 0 0 270)
			(layer "F.SilkS")
			(hide yes)
			(effects
				(font
					(size 1.27 1.27)
				)
			)
		)
		(property "Value" "PCA9511ADP-T-GP"
			(at 0 -13.1572 270)
			(unlocked yes)
			(layer "F.Fab")
			(hide yes)
			(effects
				(font
					(size 1.016 1.016)
					(thickness 0.1524)
				)
			)
		)
		(property "Device Type" "SSOIC8-2H44"
			(at 0 -15.1892 270)
			(unlocked yes)
			(layer "F.Fab")
			(hide yes)
			(effects
				(font
					(size 1.016 1.016)
					(thickness 0.1524)
				)
			)
		)
		(duplicate_pad_numbers_are_jumpers no)
		(fp_line
			(start -1.7018 1.0414)
			(end -1.7018 2.9718)
			(stroke
				(width 0.635)
				(type default)
			)
			(layer "F.SilkS")
		)
		(fp_line
			(start -1.9304 1.016)
			(end -1.9304 -1.016)
			(stroke
				(width 0.1524)
				(type default)
			)
			(layer "F.SilkS")
		)
		(fp_line
			(start 1.0922 1.016)
			(end -1.9304 1.016)
			(stroke
				(width 0.1524)
				(type default)
			)
			(layer "F.SilkS")
		)
		(fp_line
			(start -1.524 0)
			(end -1.9304 0.4064)
			(stroke
				(width 0.1524)
				(type default)
			)
			(layer "F.SilkS")
		)
		(fp_line
			(start -1.524 0)
			(end -1.9304 -0.4064)
			(stroke
				(width 0.1524)
				(type default)
			)
			(layer "F.SilkS")
		)
		(fp_line
			(start -1.9304 -1.016)
			(end 1.0922 -1.016)
			(stroke
				(width 0.1524)
				(type default)
			)
			(layer "F.SilkS")
		)
		(fp_line
			(start 1.0922 -1.016)
			(end 1.0922 1.016)
			(stroke
				(width 0.1524)
				(type default)
			)
			(layer "F.SilkS")
		)
		(fp_poly
			(pts
				(xy -1.1938 -1.016) (xy 1.0922 -1.016) (xy 1.0922 1.016) (xy -1.1938 1.016)
			)
			(stroke
				(width 0)
				(type default)
			)
			(fill yes)
			(layer "F.SilkS")
		)
		(fp_rect
			(start -2.0066 3.3401)
			(end 2.0066 -3.3401)
			(stroke
				(width 0)
				(type default)
			)
			(fill no)
			(layer "F.CrtYd")
		)
		(fp_poly
			(pts
				(xy -2.0066 -3.3401) (xy 2.0066 -3.3401) (xy 2.0066 3.3401) (xy -2.0066 3.3401)
			)
			(stroke
				(width 0)
				(type default)
			)
			(fill no)
			(layer "F.Fab")
		)
		(pad "1" smd rect
			(at -0.97536 2.0701 270)
			(size 0.4064 1.524)
			(layers "F.Cu" "F.Mask" "F.Paste")
			(net "I2C_B_BUFF_EN")
		)
		(pad "2" smd rect
			(at -0.32512 2.0701 270)
			(size 0.4064 1.524)
			(layers "F.Cu" "F.Mask" "F.Paste")
			(net "BMC_I2C_B_SCL")
		)
		(pad "3" smd rect
			(at 0.32512 2.0701 270)
			(size 0.4064 1.524)
			(layers "F.Cu" "F.Mask" "F.Paste")
			(net "SAS_I2C_B_BUF_SCL")
		)
		(pad "4" smd rect
			(at 0.97536 2.0701 270)
			(size 0.4064 1.524)
			(layers "F.Cu" "F.Mask" "F.Paste")
			(net "GND")
		)
		(pad "5" smd rect
			(at 0.97536 -2.0701 270)
			(size 0.4064 1.524)
			(layers "F.Cu" "F.Mask" "F.Paste")
			(net "I2C_B_BUF_READY")
		)
		(pad "6" smd rect
			(at 0.32512 -2.0701 270)
			(size 0.4064 1.524)
			(layers "F.Cu" "F.Mask" "F.Paste")
			(net "SAS_I2C_B_BUF_SDA")
		)
		(pad "7" smd rect
			(at -0.32512 -2.0701 270)
			(size 0.4064 1.524)
			(layers "F.Cu" "F.Mask" "F.Paste")
			(net "BMC_I2C_B_SDA")
		)
		(pad "8" smd rect
			(at -0.97536 -2.0701 270)
			(size 0.4064 1.524)
			(layers "F.Cu" "F.Mask" "F.Paste")
			(net "P3V3_STBY")
		)
	)
	(footprint ""
		(layer "F.Cu")
		(at 17.730216 -213.79688)
		(property "Reference" "R631"
			(at 0 0 0)
			(layer "F.SilkS")
			(hide yes)
			(effects
				(font
					(size 1.27 1.27)
				)
			)
		)
		(property "Value" "4K7R2F-GP"
			(at 0.064008 -3.993896 0)
			(unlocked yes)
			(layer "F.Fab")
			(hide yes)
			(effects
				(font
					(size 1.016 1.016)
					(thickness 0.1524)
				)
			)
		)
		(property "Device Type" "R402H16"
			(at 0.064008 -5.517896 0)
			(unlocked yes)
			(layer "F.Fab")
			(hide yes)
			(effects
				(font
					(size 1.016 1.016)
					(thickness 0.1524)
				)
			)
		)
		(duplicate_pad_numbers_are_jumpers no)
		(fp_line
			(start -0.508 -0.9398)
			(end -0.508 0.9398)
			(stroke
				(width 0.1524)
				(type default)
			)
			(layer "F.SilkS")
		)
		(fp_line
			(start 0.508 -0.9398)
			(end -0.508 -0.9398)
			(stroke
				(width 0.1524)
				(type default)
			)
			(layer "F.SilkS")
		)
		(fp_rect
			(start -0.508 0.9398)
			(end 0.508 -0.9398)
			(stroke
				(width 0)
				(type default)
			)
			(fill no)
			(layer "F.CrtYd")
		)
		(fp_rect
			(start -0.508 0.9398)
			(end 0.508 -0.9398)
			(stroke
				(width 0)
				(type default)
			)
			(fill no)
			(layer "F.Fab")
		)
		(pad "1" smd custom
			(at 0 -0.4445)
			(size 0.1397 0.1397)
			(layers "F.Cu" "F.Mask" "F.Paste")
			(net "IO_EXP_HDD_PWR_A0")
			(options
				(clearance outline)
				(anchor circle)
			)
			(primitives
				(gr_poly
					(pts
						(arc
							(start -0.1778 -0.2794)
							(mid -0.249642 -0.249642)
							(end -0.2794 -0.1778)
						)
						(arc
							(start -0.2794 0.1778)
							(mid -0.249642 0.249642)
							(end -0.1778 0.2794)
						)
						(arc
							(start 0.1778 0.2794)
							(mid 0.249642 0.249642)
							(end 0.2794 0.1778)
						)
						(arc
							(start 0.2794 -0.1778)
							(mid 0.249642 -0.249642)
							(end 0.1778 -0.2794)
						)
					)
					(width 0)
					(fill yes)
				)
			)
		)
		(pad "2" smd custom
			(at 0 0.4445)
			(size 0.1397 0.1397)
			(layers "F.Cu" "F.Mask" "F.Paste")
			(net "GND")
			(options
				(clearance outline)
				(anchor circle)
			)
			(primitives
				(gr_poly
					(pts
						(arc
							(start -0.1778 -0.2794)
							(mid -0.249642 -0.249642)
							(end -0.2794 -0.1778)
						)
						(arc
							(start -0.2794 0.1778)
							(mid -0.249642 0.249642)
							(end -0.1778 0.2794)
						)
						(arc
							(start 0.1778 0.2794)
							(mid 0.249642 0.249642)
							(end 0.2794 0.1778)
						)
						(arc
							(start 0.2794 -0.1778)
							(mid 0.249642 -0.249642)
							(end 0.1778 -0.2794)
						)
					)
					(width 0)
					(fill yes)
				)
			)
		)
	)
	(footprint ""
		(layer "F.Cu")
		(at 341.786718 -144.122648 -90)
		(property "Reference" "R701"
			(at 0 0 270)
			(layer "F.SilkS")
			(hide yes)
			(effects
				(font
					(size 1.27 1.27)
				)
			)
		)
		(property "Value" "1MR2F-GP"
			(at 0.064008 -3.993896 270)
			(unlocked yes)
			(layer "F.Fab")
			(hide yes)
			(effects
				(font
					(size 1.016 1.016)
					(thickness 0.1524)
				)
			)
		)
		(property "Device Type" "R402H16"
			(at 0.064008 -5.517896 270)
			(unlocked yes)
			(layer "F.Fab")
			(hide yes)
			(effects
				(font
					(size 1.016 1.016)
					(thickness 0.1524)
				)
			)
		)
		(duplicate_pad_numbers_are_jumpers no)
		(fp_line
			(start -0.508 -0.9398)
			(end -0.508 0.9398)
			(stroke
				(width 0.1524)
				(type default)
			)
			(layer "F.SilkS")
		)
		(fp_line
			(start 0.508 -0.9398)
			(end -0.508 -0.9398)
			(stroke
				(width 0.1524)
				(type default)
			)
			(layer "F.SilkS")
		)
		(fp_rect
			(start -0.508 0.9398)
			(end 0.508 -0.9398)
			(stroke
				(width 0)
				(type default)
			)
			(fill no)
			(layer "F.CrtYd")
		)
		(fp_rect
			(start -0.508 0.9398)
			(end 0.508 -0.9398)
			(stroke
				(width 0)
				(type default)
			)
			(fill no)
			(layer "F.Fab")
		)
		(pad "1" smd custom
			(at 0 -0.4445 270)
			(size 0.1397 0.1397)
			(layers "F.Cu" "F.Mask" "F.Paste")
			(net "USB_HUB_XTAL_IN")
			(options
				(clearance outline)
				(anchor circle)
			)
			(primitives
				(gr_poly
					(pts
						(arc
							(start -0.1778 -0.2794)
							(mid -0.249642 -0.249642)
							(end -0.2794 -0.1778)
						)
						(arc
							(start -0.2794 0.1778)
							(mid -0.249642 0.249642)
							(end -0.1778 0.2794)
						)
						(arc
							(start 0.1778 0.2794)
							(mid 0.249642 0.249642)
							(end 0.2794 0.1778)
						)
						(arc
							(start 0.2794 -0.1778)
							(mid 0.249642 -0.249642)
							(end 0.1778 -0.2794)
						)
					)
					(width 0)
					(fill yes)
				)
			)
		)
		(pad "2" smd custom
			(at 0 0.4445 270)
			(size 0.1397 0.1397)
			(layers "F.Cu" "F.Mask" "F.Paste")
			(net "USB_HUB_XTAL_OUT")
			(options
				(clearance outline)
				(anchor circle)
			)
			(primitives
				(gr_poly
					(pts
						(arc
							(start -0.1778 -0.2794)
							(mid -0.249642 -0.249642)
							(end -0.2794 -0.1778)
						)
						(arc
							(start -0.2794 0.1778)
							(mid -0.249642 0.249642)
							(end -0.1778 0.2794)
						)
						(arc
							(start 0.1778 0.2794)
							(mid 0.249642 0.249642)
							(end 0.2794 0.1778)
						)
						(arc
							(start 0.2794 -0.1778)
							(mid 0.249642 -0.249642)
							(end 0.1778 -0.2794)
						)
					)
					(width 0)
					(fill yes)
				)
			)
		)
	)
)
